(kicad_pcb
	(version 20241229)
	(generator "pcbnew")
	(generator_version "9.0")
	(general
		(thickness 1.552)
		(legacy_teardrops no)
	)
	(paper "A4")
	(title_block
		(date "2023-07-25")
		(rev "1.1.4")
		(comment 9 "footprint 75 of 379 (U15), pads 1-88 of 100")
	)
	(layers
		(0 "F.Cu" signal)
		(4 "In1.Cu" signal)
		(6 "In2.Cu" signal)
		(8 "In3.Cu" signal)
		(10 "In4.Cu" signal)
		(12 "In5.Cu" signal)
		(14 "In6.Cu" signal)
		(2 "B.Cu" signal)
		(9 "F.Adhes" user "F.Adhesive")
		(11 "B.Adhes" user "B.Adhesive")
		(13 "F.Paste" user)
		(15 "B.Paste" user)
		(5 "F.SilkS" user "F.Silkscreen")
		(7 "B.SilkS" user "B.Silkscreen")
		(1 "F.Mask" user)
		(3 "B.Mask" user)
		(17 "Dwgs.User" user "User.Drawings")
		(19 "Cmts.User" user "User.Comments")
		(21 "Eco1.User" user "User.Eco1")
		(23 "Eco2.User" user "User.Eco2")
		(25 "Edge.Cuts" user)
		(27 "Margin" user)
		(31 "F.CrtYd" user "F.Courtyard")
		(29 "B.CrtYd" user "B.Courtyard")
		(35 "F.Fab" user)
		(33 "B.Fab" user)
	)
	(footprint "antmicro-footprints:BGA-100_11x11mm_Layout10x10_P1mm"
		(layer "F.Cu")
		(at 95.609 77.893)
		(property "Reference" "U15"
			(at 0 -6.15 0)
			(layer "F.SilkS")
			(effects
				(font
					(size 0.7 0.7)
					(thickness 0.15)
				)
				(justify left bottom)
			)
		)
		(property "Value" "GS2971A"
			(at 0 7 0)
			(layer "F.Fab")
			(effects
				(font
					(size 0.7 0.7)
					(thickness 0.15)
				)
				(justify left bottom)
			)
		)
		(property "Datasheet" "https://semtech.my.salesforce.com/sfc/p/#E0000000JelG/a/44000000MD3i/kpmMkrmUWgHlbCOwdLzVohMm1SDPoVH85guEGK.KXTc"
			(at 0 0 0)
			(layer "F.Fab")
			(hide yes)
			(effects
				(font
					(size 1.27 1.27)
					(thickness 0.15)
				)
			)
		)
		(property "Description" "SDI receiver"
			(at 0 0 0)
			(layer "F.Fab")
			(hide yes)
			(effects
				(font
					(size 1.27 1.27)
					(thickness 0.15)
				)
			)
		)
		(property "Author" "Antmicro"
			(at 0 0 0)
			(layer "F.Fab")
			(hide yes)
			(effects
				(font
					(size 1 1)
					(thickness 0.15)
				)
			)
		)
		(property "License" "Apache-2.0"
			(at 0 0 0)
			(layer "F.Fab")
			(hide yes)
			(effects
				(font
					(size 1 1)
					(thickness 0.15)
				)
			)
		)
		(property "MPN" "GS2971A"
			(at 0 0 0)
			(layer "F.Fab")
			(hide yes)
			(effects
				(font
					(size 1 1)
					(thickness 0.15)
				)
			)
		)
		(property "Manufacturer" "Semtech"
			(at 0 0 0)
			(layer "F.Fab")
			(hide yes)
			(effects
				(font
					(size 1 1)
					(thickness 0.15)
				)
			)
		)
		(sheetname "/SDI/")
		(sheetfile "sdi.kicad_sch")
		(attr smd)
		(pad "A1" smd circle
			(at -4.518 -4.494)
			(size 0.5 0.5)
			(layers "F.Cu" "F.Mask" "F.Paste")
			(net 242 "Net-(U15B-VBG)")
			(pinfunction "VBG")
			(pintype "input")
		)
		(pad "A2" smd circle
			(at -3.519 -4.494)
			(size 0.5 0.5)
			(layers "F.Cu" "F.Mask" "F.Paste")
			(net 156 "Net-(U15B-LF)")
			(pinfunction "LF")
			(pintype "input")
		)
		(pad "A3" smd circle
			(at -2.519 -4.494)
			(size 0.5 0.5)
			(layers "F.Cu" "F.Mask" "F.Paste")
			(net 288 "Net-(U15B-LB_CONT)")
			(pinfunction "LB_CONT")
			(pintype "input")
		)
		(pad "A4" smd circle
			(at -1.518 -4.494)
			(size 0.5 0.5)
			(layers "F.Cu" "F.Mask" "F.Paste")
			(net 244 "Net-(U15C-VCO_{VDD})")
			(pinfunction "VCO_{VDD}")
			(pintype "power_in")
		)
		(pad "A5" smd circle
			(at -0.519 -4.494)
			(size 0.5 0.5)
			(layers "F.Cu" "F.Mask" "F.Paste")
			(net 214 "/SDI/SDI_STAT0")
			(pinfunction "STAT0")
			(pintype "output")
		)
		(pad "A6" smd circle
			(at 0.481 -4.494)
			(size 0.5 0.5)
			(layers "F.Cu" "F.Mask" "F.Paste")
			(net 217 "/SDI/SDI_STAT1")
			(pinfunction "STAT1")
			(pintype "output")
		)
		(pad "A7" smd circle
			(at 1.481 -4.494)
			(size 0.5 0.5)
			(layers "F.Cu" "F.Mask" "F.Paste")
			(net 2 "+3V3")
			(pinfunction "IO_{VDD}")
			(pintype "power_in")
		)
		(pad "A8" smd circle
			(at 2.482 -4.494)
			(size 0.5 0.5)
			(layers "F.Cu" "F.Mask" "F.Paste")
			(net 197 "/SDI/SDI_PCLK")
			(pinfunction "PCLK")
			(pintype "output")
		)
		(pad "A9" smd circle
			(at 3.482 -4.494)
			(size 0.5 0.5)
			(layers "F.Cu" "F.Mask" "F.Paste")
			(net 216 "/SDI/SDI_D18")
			(pinfunction "DOUT18")
			(pintype "output")
		)
		(pad "A10" smd circle
			(at 4.482 -4.494)
			(size 0.5 0.5)
			(layers "F.Cu" "F.Mask" "F.Paste")
			(net 215 "/SDI/SDI_D17")
			(pinfunction "DOUT17")
			(pintype "output")
		)
		(pad "B1" smd circle
			(at -4.518 -3.493)
			(size 0.5 0.5)
			(layers "F.Cu" "F.Mask" "F.Paste")
			(net 2 "+3V3")
			(pinfunction "A_{VDD}")
			(pintype "power_in")
		)
		(pad "B2" smd circle
			(at -3.519 -3.493)
			(size 0.5 0.5)
			(layers "F.Cu" "F.Mask" "F.Paste")
			(net 3 "+1V2")
			(pinfunction "PLL_{VDD}")
			(pintype "power_in")
		)
		(pad "B3" smd circle
			(at -2.519 -3.493)
			(size 0.5 0.5)
			(layers "F.Cu" "F.Mask" "F.Paste")
			(net 57 "unconnected-(U15B-RSV-PadB3)")
			(pinfunction "RSV")
			(pintype "no_connect")
		)
		(pad "B4" smd circle
			(at -1.518 -3.493)
			(size 0.5 0.5)
			(layers "F.Cu" "F.Mask" "F.Paste")
			(net 1 "GND")
			(pinfunction "VCO_{GND}")
			(pintype "power_in")
		)
		(pad "B5" smd circle
			(at -0.519 -3.493)
			(size 0.5 0.5)
			(layers "F.Cu" "F.Mask" "F.Paste")
			(net 212 "/SDI/SDI_STAT2")
			(pinfunction "STAT2")
			(pintype "output")
		)
		(pad "B6" smd circle
			(at 0.481 -3.493)
			(size 0.5 0.5)
			(layers "F.Cu" "F.Mask" "F.Paste")
			(net 219 "/SDI/SDI_STAT3")
			(pinfunction "STAT3")
			(pintype "output")
		)
		(pad "B7" smd circle
			(at 1.481 -3.493)
			(size 0.5 0.5)
			(layers "F.Cu" "F.Mask" "F.Paste")
			(net 1 "GND")
			(pinfunction "IO_{GND}")
			(pintype "power_in")
		)
		(pad "B8" smd circle
			(at 2.482 -3.493)
			(size 0.5 0.5)
			(layers "F.Cu" "F.Mask" "F.Paste")
			(net 213 "/SDI/SDI_D19")
			(pinfunction "DOUT19")
			(pintype "output")
		)
		(pad "B9" smd circle
			(at 3.482 -3.493)
			(size 0.5 0.5)
			(layers "F.Cu" "F.Mask" "F.Paste")
			(net 211 "/SDI/SDI_D16")
			(pinfunction "DOUT16")
			(pintype "output")
		)
		(pad "B10" smd circle
			(at 4.482 -3.493)
			(size 0.5 0.5)
			(layers "F.Cu" "F.Mask" "F.Paste")
			(net 210 "/SDI/SDI_D15")
			(pinfunction "DOUT15")
			(pintype "output")
		)
		(pad "C1" smd circle
			(at -4.518 -2.493)
			(size 0.5 0.5)
			(layers "F.Cu" "F.Mask" "F.Paste")
			(net 7 "/SDI/SDI_P")
			(pinfunction "SDI+")
			(pintype "input")
		)
		(pad "C2" smd circle
			(at -3.519 -2.493)
			(size 0.5 0.5)
			(layers "F.Cu" "F.Mask" "F.Paste")
			(net 1 "GND")
			(pinfunction "A_{GND}")
			(pintype "power_in")
		)
		(pad "C3" smd circle
			(at -2.519 -2.493)
			(size 0.5 0.5)
			(layers "F.Cu" "F.Mask" "F.Paste")
			(net 3 "+1V2")
			(pinfunction "PLL_{VDD}")
			(pintype "passive")
		)
		(pad "C4" smd circle
			(at -1.518 -2.493)
			(size 0.5 0.5)
			(layers "F.Cu" "F.Mask" "F.Paste")
			(net 3 "+1V2")
			(pinfunction "PLL_{VDD}")
			(pintype "passive")
		)
		(pad "C5" smd circle
			(at -0.519 -2.493)
			(size 0.5 0.5)
			(layers "F.Cu" "F.Mask" "F.Paste")
			(net 218 "/SDI/SDI_STAT4")
			(pinfunction "STAT4")
			(pintype "output")
		)
		(pad "C6" smd circle
			(at 0.481 -2.493)
			(size 0.5 0.5)
			(layers "F.Cu" "F.Mask" "F.Paste")
			(net 183 "/SDI/SDI_STAT5")
			(pinfunction "STAT5")
			(pintype "output")
		)
		(pad "C7" smd circle
			(at 1.481 -2.493)
			(size 0.5 0.5)
			(layers "F.Cu" "F.Mask" "F.Paste")
			(net 175 "/SDI/RESET_TRST")
			(pinfunction "RESET_TRST")
			(pintype "input")
		)
		(pad "C8" smd circle
			(at 2.482 -2.493)
			(size 0.5 0.5)
			(layers "F.Cu" "F.Mask" "F.Paste")
			(net 204 "/SDI/SDI_D12")
			(pinfunction "DOUT12")
			(pintype "output")
		)
		(pad "C9" smd circle
			(at 3.482 -2.493)
			(size 0.5 0.5)
			(layers "F.Cu" "F.Mask" "F.Paste")
			(net 206 "/SDI/SDI_D14")
			(pinfunction "DOUT14")
			(pintype "output")
		)
		(pad "C10" smd circle
			(at 4.482 -2.493)
			(size 0.5 0.5)
			(layers "F.Cu" "F.Mask" "F.Paste")
			(net 207 "/SDI/SDI_D13")
			(pinfunction "DOUT13")
			(pintype "output")
		)
		(pad "D1" smd circle
			(at -4.518 -1.494)
			(size 0.5 0.5)
			(layers "F.Cu" "F.Mask" "F.Paste")
			(net 8 "/SDI/SDI_N")
			(pinfunction "SDI-")
			(pintype "input")
		)
		(pad "D2" smd circle
			(at -3.519 -1.494)
			(size 0.5 0.5)
			(layers "F.Cu" "F.Mask" "F.Paste")
			(net 1 "GND")
			(pinfunction "A_{GND}")
			(pintype "passive")
		)
		(pad "D3" smd circle
			(at -2.519 -1.494)
			(size 0.5 0.5)
			(layers "F.Cu" "F.Mask" "F.Paste")
			(net 1 "GND")
			(pinfunction "A_{GND}")
			(pintype "passive")
		)
		(pad "D4" smd circle
			(at -1.518 -1.494)
			(size 0.5 0.5)
			(layers "F.Cu" "F.Mask" "F.Paste")
			(net 1 "GND")
			(pinfunction "PLL_{GND}")
			(pintype "power_in")
		)
		(pad "D5" smd circle
			(at -0.519 -1.494)
			(size 0.5 0.5)
			(layers "F.Cu" "F.Mask" "F.Paste")
			(net 1 "GND")
			(pinfunction "CORE_{GND}")
			(pintype "power_in")
		)
		(pad "D6" smd circle
			(at 0.481 -1.494)
			(size 0.5 0.5)
			(layers "F.Cu" "F.Mask" "F.Paste")
			(net 3 "+1V2")
			(pinfunction "CORE_{VDD}")
			(pintype "power_in")
		)
		(pad "D7" smd circle
			(at 1.481 -1.494)
			(size 0.5 0.5)
			(layers "F.Cu" "F.Mask" "F.Paste")
			(net 177 "/SDI/SW_EN")
			(pinfunction "SW_EN")
			(pintype "input")
		)
		(pad "D8" smd circle
			(at 2.482 -1.494)
			(size 0.5 0.5)
			(layers "F.Cu" "F.Mask" "F.Paste")
			(net 208 "/SDI/JTAG{slash}~{HOST}")
			(pinfunction "JTAG/~{HOST}")
			(pintype "input")
		)
		(pad "D9" smd circle
			(at 3.482 -1.494)
			(size 0.5 0.5)
			(layers "F.Cu" "F.Mask" "F.Paste")
			(net 1 "GND")
			(pinfunction "IO_{GND}")
			(pintype "passive")
		)
		(pad "D10" smd circle
			(at 4.482 -1.494)
			(size 0.5 0.5)
			(layers "F.Cu" "F.Mask" "F.Paste")
			(net 2 "+3V3")
			(pinfunction "IO_{VDD}")
			(pintype "passive")
		)
		(pad "E1" smd circle
			(at -4.518 -0.493)
			(size 0.5 0.5)
			(layers "F.Cu" "F.Mask" "F.Paste")
			(net 2 "+3V3")
			(pinfunction "EQ_{VDD}")
			(pintype "power_in")
		)
		(pad "E2" smd circle
			(at -3.519 -0.493)
			(size 0.5 0.5)
			(layers "F.Cu" "F.Mask" "F.Paste")
			(net 1 "GND")
			(pinfunction "EQ_{GND}")
			(pintype "power_in")
		)
		(pad "E3" smd circle
			(at -2.519 -0.493)
			(size 0.5 0.5)
			(layers "F.Cu" "F.Mask" "F.Paste")
			(net 1 "GND")
			(pinfunction "A_{GND}")
			(pintype "passive")
		)
		(pad "E4" smd circle
			(at -1.518 -0.493)
			(size 0.5 0.5)
			(layers "F.Cu" "F.Mask" "F.Paste")
			(net 1 "GND")
			(pinfunction "PLL_{GND}")
			(pintype "passive")
		)
		(pad "E5" smd circle
			(at -0.519 -0.493)
			(size 0.5 0.5)
			(layers "F.Cu" "F.Mask" "F.Paste")
			(net 1 "GND")
			(pinfunction "CORE_{GND}")
			(pintype "passive")
		)
		(pad "E6" smd circle
			(at 0.481 -0.493)
			(size 0.5 0.5)
			(layers "F.Cu" "F.Mask" "F.Paste")
			(net 3 "+1V2")
			(pinfunction "CORE_{VDD}")
			(pintype "passive")
		)
		(pad "E7" smd circle
			(at 1.481 -0.493)
			(size 0.5 0.5)
			(layers "F.Cu" "F.Mask" "F.Paste")
			(net 181 "/SDI/SDOUT_TDO")
			(pinfunction "SDOUT_TDO")
			(pintype "output")
		)
		(pad "E8" smd circle
			(at 2.482 -0.493)
			(size 0.5 0.5)
			(layers "F.Cu" "F.Mask" "F.Paste")
			(net 182 "/SDI/SDIN_TDI")
			(pinfunction "SDIN_TDI")
			(pintype "input")
		)
		(pad "E9" smd circle
			(at 3.482 -0.493)
			(size 0.5 0.5)
			(layers "F.Cu" "F.Mask" "F.Paste")
			(net 203 "/SDI/SDI_D10")
			(pinfunction "DOUT10")
			(pintype "output")
		)
		(pad "E10" smd circle
			(at 4.482 -0.493)
			(size 0.5 0.5)
			(layers "F.Cu" "F.Mask" "F.Paste")
			(net 205 "/SDI/SDI_D11")
			(pinfunction "DOUT11")
			(pintype "output")
		)
		(pad "F1" smd circle
			(at -4.518 0.506)
			(size 0.5 0.5)
			(layers "F.Cu" "F.Mask" "F.Paste")
			(net 292 "/SDI/AGC_P")
			(pinfunction "AGC+")
			(pintype "passive")
		)
		(pad "F2" smd circle
			(at -3.519 0.506)
			(size 0.5 0.5)
			(layers "F.Cu" "F.Mask" "F.Paste")
			(net 59 "unconnected-(U15B-RSV-PadF2)")
			(pinfunction "RSV")
			(pintype "no_connect")
		)
		(pad "F3" smd circle
			(at -2.519 0.506)
			(size 0.5 0.5)
			(layers "F.Cu" "F.Mask" "F.Paste")
			(net 1 "GND")
			(pinfunction "A_{GND}")
			(pintype "passive")
		)
		(pad "F4" smd circle
			(at -1.518 0.506)
			(size 0.5 0.5)
			(layers "F.Cu" "F.Mask" "F.Paste")
			(net 1 "GND")
			(pinfunction "PLL_{GND}")
			(pintype "passive")
		)
		(pad "F5" smd circle
			(at -0.519 0.506)
			(size 0.5 0.5)
			(layers "F.Cu" "F.Mask" "F.Paste")
			(net 1 "GND")
			(pinfunction "CORE_{GND}")
			(pintype "passive")
		)
		(pad "F6" smd circle
			(at 0.481 0.506)
			(size 0.5 0.5)
			(layers "F.Cu" "F.Mask" "F.Paste")
			(net 3 "+1V2")
			(pinfunction "CORE_{VDD}")
			(pintype "passive")
		)
		(pad "F7" smd circle
			(at 1.481 0.506)
			(size 0.5 0.5)
			(layers "F.Cu" "F.Mask" "F.Paste")
			(net 178 "/SDI/~{CS_TMS}")
			(pinfunction "~{CS}_TMS")
			(pintype "input")
		)
		(pad "F8" smd circle
			(at 2.482 0.506)
			(size 0.5 0.5)
			(layers "F.Cu" "F.Mask" "F.Paste")
			(net 179 "/SDI/SCLK_TCK")
			(pinfunction "SCLK_TCK")
			(pintype "input")
		)
		(pad "F9" smd circle
			(at 3.482 0.506)
			(size 0.5 0.5)
			(layers "F.Cu" "F.Mask" "F.Paste")
			(net 195 "/SDI/SDI_D8")
			(pinfunction "DOUT08")
			(pintype "output")
		)
		(pad "F10" smd circle
			(at 4.482 0.506)
			(size 0.5 0.5)
			(layers "F.Cu" "F.Mask" "F.Paste")
			(net 202 "/SDI/SDI_D9")
			(pinfunction "DOUT09")
			(pintype "output")
		)
		(pad "G1" smd circle
			(at -4.518 1.507)
			(size 0.5 0.5)
			(layers "F.Cu" "F.Mask" "F.Paste")
			(net 291 "/SDI/AGC_N")
			(pinfunction "AGC-")
			(pintype "passive")
		)
		(pad "G2" smd circle
			(at -3.519 1.507)
			(size 0.5 0.5)
			(layers "F.Cu" "F.Mask" "F.Paste")
			(net 1 "GND")
			(pinfunction "A_{GND}")
			(pintype "passive")
		)
		(pad "G3" smd circle
			(at -2.519 1.507)
			(size 0.5 0.5)
			(layers "F.Cu" "F.Mask" "F.Paste")
			(net 209 "/SDI/~{RC_BYP}")
			(pinfunction "~{RC_BYP}")
			(pintype "input")
		)
		(pad "G4" smd circle
			(at -1.518 1.507)
			(size 0.5 0.5)
			(layers "F.Cu" "F.Mask" "F.Paste")
			(net 1 "GND")
			(pinfunction "CORE_{GND}")
			(pintype "passive")
		)
		(pad "G5" smd circle
			(at -0.519 1.507)
			(size 0.5 0.5)
			(layers "F.Cu" "F.Mask" "F.Paste")
			(net 1 "GND")
			(pinfunction "CORE_{GND}")
			(pintype "passive")
		)
		(pad "G6" smd circle
			(at 0.481 1.507)
			(size 0.5 0.5)
			(layers "F.Cu" "F.Mask" "F.Paste")
			(net 3 "+1V2")
			(pinfunction "CORE_{VDD}")
			(pintype "passive")
		)
		(pad "G7" smd circle
			(at 1.481 1.507)
			(size 0.5 0.5)
			(layers "F.Cu" "F.Mask" "F.Paste")
			(net 201 "/SDI/~{SMPTE_BYPASS}")
			(pinfunction "~{SMPTE_BYPASS}")
			(pintype "bidirectional")
		)
		(pad "G8" smd circle
			(at 2.482 1.507)
			(size 0.5 0.5)
			(layers "F.Cu" "F.Mask" "F.Paste")
			(net 193 "/SDI/DVB_ASI")
			(pinfunction "DVB_ASI")
			(pintype "bidirectional")
		)
		(pad "G9" smd circle
			(at 3.482 1.507)
			(size 0.5 0.5)
			(layers "F.Cu" "F.Mask" "F.Paste")
			(net 1 "GND")
			(pinfunction "IO_{GND}")
			(pintype "passive")
		)
		(pad "G10" smd circle
			(at 4.482 1.507)
			(size 0.5 0.5)
			(layers "F.Cu" "F.Mask" "F.Paste")
			(net 2 "+3V3")
			(pinfunction "IO_{VDD}")
			(pintype "passive")
		)
		(pad "H1" smd circle
			(at -4.518 2.507)
			(size 0.5 0.5)
			(layers "F.Cu" "F.Mask" "F.Paste")
			(net 2 "+3V3")
			(pinfunction "BUFF_{VDD}")
			(pintype "power_in")
		)
		(pad "H2" smd circle
			(at -3.519 2.507)
			(size 0.5 0.5)
			(layers "F.Cu" "F.Mask" "F.Paste")
			(net 1 "GND")
			(pinfunction "BUFF_{GND}")
			(pintype "power_in")
		)
		(pad "H3" smd circle
			(at -2.519 2.507)
			(size 0.5 0.5)
			(layers "F.Cu" "F.Mask" "F.Paste")
			(net 198 "/SDI/AUDIO_EN{slash}~{DIS}")
			(pinfunction "AUDIO_EN/~{DIS}")
			(pintype "input")
		)
		(pad "H4" smd circle
			(at -1.518 2.507)
			(size 0.5 0.5)
			(layers "F.Cu" "F.Mask" "F.Paste")
			(net 21 "AUDIO_WCLK")
			(pinfunction "WCLK")
			(pintype "output")
		)
		(pad "H5" smd circle
			(at -0.519 2.507)
			(size 0.5 0.5)
			(layers "F.Cu" "F.Mask" "F.Paste")
			(net 180 "/SDI/TIM_861")
			(pinfunction "TIM_861")
			(pintype "input")
		)
		(pad "H6" smd circle
			(at 0.481 2.507)
			(size 0.5 0.5)
			(layers "F.Cu" "F.Mask" "F.Paste")
			(net 377 "Net-(U15B-XTAL_OUT)")
			(pinfunction "XTAL_OUT")
			(pintype "output")
		)
		(pad "H7" smd circle
			(at 1.481 2.507)
			(size 0.5 0.5)
			(layers "F.Cu" "F.Mask" "F.Paste")
			(net 200 "/SDI/20bit{slash}~{10bit}")
			(pinfunction "20BIT/~{10BIT}")
			(pintype "input")
		)
		(pad "H8" smd circle
			(at 2.482 2.507)
			(size 0.5 0.5)
			(layers "F.Cu" "F.Mask" "F.Paste")
			(net 199 "/SDI/IOPROC_EN{slash}~{DIS}")
			(pinfunction "IOPROC_EN/~{DIS}")
			(pintype "input")
		)
		(pad "H9" smd circle
			(at 3.482 2.507)
			(size 0.5 0.5)
			(layers "F.Cu" "F.Mask" "F.Paste")
			(net 196 "/SDI/SDI_D6")
			(pinfunction "DOUT06")
			(pintype "output")
		)
		(pad "H10" smd circle
			(at 4.482 2.507)
			(size 0.5 0.5)
			(layers "F.Cu" "F.Mask" "F.Paste")
			(net 194 "/SDI/SDI_D7")
			(pinfunction "DOUT07")
			(pintype "output")
		)
		(pad "J1" smd circle
			(at -4.518 3.507)
			(size 0.5 0.5)
			(layers "F.Cu" "F.Mask" "F.Paste")
			(net 47 "/SDI/SDO_P")
			(pinfunction "SDO+")
			(pintype "output")
		)
		(pad "J2" smd circle
			(at -3.519 3.507)
			(size 0.5 0.5)
			(layers "F.Cu" "F.Mask" "F.Paste")
			(net 185 "/SDI/SDO_EN{slash}DIS")
			(pinfunction "SDO_EN/DIS")
			(pintype "input")
		)
		(pad "J3" smd circle
			(at -2.519 3.507)
			(size 0.5 0.5)
			(layers "F.Cu" "F.Mask" "F.Paste")
			(net 22 "AUDIO_OUT_CH1_2")
			(pinfunction "AOUT_{1/2}")
			(pintype "output")
		)
		(pad "J4" smd circle
			(at -1.518 3.507)
			(size 0.5 0.5)
			(layers "F.Cu" "F.Mask" "F.Paste")
			(net 20 "AUDIO_ACLK")
			(pinfunction "ACLK")
			(pintype "output")
		)
		(pad "J5" smd circle
			(at -0.519 3.507)
			(size 0.5 0.5)
			(layers "F.Cu" "F.Mask" "F.Paste")
			(net 23 "AUDIO_OUT_CH5_6")
			(pinfunction "AOUT_{5/6}")
			(pintype "output")
		)
		(pad "J6" smd circle
			(at 0.481 3.507)
			(size 0.5 0.5)
			(layers "F.Cu" "F.Mask" "F.Paste")
			(net 46 "/SDI/XTAL2")
			(pinfunction "XTAL2")
			(pintype "input")
		)
		(pad "J7" smd circle
			(at 1.481 3.507)
			(size 0.5 0.5)
			(layers "F.Cu" "F.Mask" "F.Paste")
			(net 1 "GND")
			(pinfunction "IO_{GND}")
			(pintype "passive")
		)
		(pad "J8" smd circle
			(at 2.482 3.507)
			(size 0.5 0.5)
			(layers "F.Cu" "F.Mask" "F.Paste")
			(net 191 "/SDI/SDI_D1")
			(pinfunction "DOUT01")
			(pintype "output")
		)
	)
)
